(kicad_pcb
	(version 20260206)
	(generator "pcbnew")
	(generator_version "10.0")
	(general
		(thickness 1.6)
		(legacy_teardrops no)
	)
	(paper "A4")
	(title_block
		(title "01162023_DA0F0TEBIF0_F0T_Expander_BD_F_brd_V02_OCP.brd")
		(comment 1 "Grand Teton / footprints 3570-3572 of 9728")
	)
	(layers
		(0 "F.Cu" signal "TOP")
		(4 "In1.Cu" signal "GND")
		(6 "In2.Cu" signal "VCC")
		(8 "In3.Cu" signal "VCC1")
		(10 "In4.Cu" signal "GND1")
		(12 "In5.Cu" signal "IN1")
		(14 "In6.Cu" signal "GND2")
		(16 "In7.Cu" signal "IN2")
		(18 "In8.Cu" signal "GND3")
		(20 "In9.Cu" signal "IN3")
		(22 "In10.Cu" signal "GND4")
		(24 "In11.Cu" signal "IN4")
		(26 "In12.Cu" signal "GND5")
		(28 "In13.Cu" signal "IN5")
		(30 "In14.Cu" signal "GND6")
		(32 "In15.Cu" signal "IN6")
		(34 "In16.Cu" signal "GND7")
		(2 "B.Cu" signal "BOTTOM")
		(9 "F.Adhes" user "F.Adhesive")
		(11 "B.Adhes" user "B.Adhesive")
		(13 "F.Paste" user "Package Geometry/Pastemask Top")
		(15 "B.Paste" user "Package Geometry/Pastemask Bottom")
		(5 "F.SilkS" user "Ref Des/Silkscreen Top")
		(7 "B.SilkS" user "Ref Des/Silkscreen Bottom")
		(1 "F.Mask" user "Board Geometry/Soldermask Top")
		(3 "B.Mask" user "Board Geometry/Soldermask Bottom")
		(17 "Dwgs.User" user "User.Drawings")
		(19 "Cmts.User" user "User.Comments")
		(21 "Eco1.User" user "User.Eco1")
		(23 "Eco2.User" user "User.Eco2")
		(25 "Edge.Cuts" user "Board Geometry/Outline")
		(27 "Margin" user)
		(31 "F.CrtYd" user "Package Geometry/Place Bound Top")
		(29 "B.CrtYd" user "Package Geometry/Place Bound Bottom")
		(35 "F.Fab" user "Ref Des/Assembly Top")
		(33 "B.Fab" user "Ref Des/Assembly Bottom")
	)
	(footprint ""
		(layer "F.Cu")
		(at 439.264806 -26.785062 180)
		(property "Reference" "J45"
			(at 4.028186 -11.14044 90)
			(unlocked yes)
			(layer "F.SilkS")
			(effects
				(font
					(size 0.7874 0.5842)
					(thickness 0.1524)
				)
			)
		)
		(property "Value" ""
			(at 0 0 180)
			(layer "F.Fab")
			(effects
				(font
					(size 1.27 1.27)
				)
			)
		)
		(duplicate_pad_numbers_are_jumpers no)
		(fp_line
			(start 3.150108 12.115038)
			(end 1.529334 12.115038)
			(stroke
				(width 0.1524)
				(type default)
			)
			(layer "F.SilkS")
		)
		(fp_line
			(start 3.074924 12.014962)
			(end 1.632204 12.014962)
			(stroke
				(width 0.1524)
				(type default)
			)
			(layer "F.SilkS")
		)
		(fp_line
			(start 1.632204 -12.014962)
			(end 3.074924 -12.014962)
			(stroke
				(width 0.1524)
				(type default)
			)
			(layer "F.SilkS")
		)
		(fp_line
			(start 1.529334 -12.115038)
			(end 3.150108 -12.115038)
			(stroke
				(width 0.1524)
				(type default)
			)
			(layer "F.SilkS")
		)
		(fp_line
			(start -1.529334 12.115038)
			(end -3.150108 12.115038)
			(stroke
				(width 0.1524)
				(type default)
			)
			(layer "F.SilkS")
		)
		(fp_line
			(start -1.632204 12.014962)
			(end -3.074924 12.014962)
			(stroke
				(width 0.1524)
				(type default)
			)
			(layer "F.SilkS")
		)
		(fp_line
			(start -3.074924 -12.014962)
			(end -1.632204 -12.014962)
			(stroke
				(width 0.1524)
				(type default)
			)
			(layer "F.SilkS")
		)
		(fp_line
			(start -3.150108 -12.115038)
			(end -1.529334 -12.115038)
			(stroke
				(width 0.1524)
				(type default)
			)
			(layer "F.SilkS")
		)
		(fp_poly
			(pts
				(xy 3.344418 -8.619236) (xy 3.76682 -9.88695) (xy 4.611878 -9.041892)
			)
			(stroke
				(width 0)
				(type default)
			)
			(fill yes)
			(layer "F.SilkS")
		)
		(fp_line
			(start 3.074924 12.014962)
			(end -3.074924 12.014962)
			(stroke
				(width 0.1)
				(type default)
			)
			(layer "F.Fab")
		)
		(fp_line
			(start 3.074924 -12.014962)
			(end 3.074924 12.014962)
			(stroke
				(width 0.1)
				(type default)
			)
			(layer "F.Fab")
		)
		(fp_line
			(start -3.074924 12.014962)
			(end -3.074924 -12.014962)
			(stroke
				(width 0.1)
				(type default)
			)
			(layer "F.Fab")
		)
		(fp_line
			(start -3.074924 -12.014962)
			(end 3.074924 -12.014962)
			(stroke
				(width 0.1)
				(type default)
			)
			(layer "F.Fab")
		)
		(fp_poly
			(pts
				(xy 3.348736 -7.994904) (xy 4.543806 -8.592566) (xy 4.543806 -7.397496)
			)
			(stroke
				(width 0)
				(type default)
			)
			(fill yes)
			(layer "F.Fab")
		)
		(pad "" np_thru_hole circle
			(at -1.75006 -9.815068 90)
			(size 1.1176 1.1176)
			(drill 1.1176)
			(layers "*.Cu" "*.Mask")
			(clearance 0.381)
			(thermal_gap 0.381)
		)
		(pad "" np_thru_hole circle
			(at 0 9.815068 90)
			(size 1.1176 1.1176)
			(drill 1.1176)
			(layers "*.Cu" "*.Mask")
			(clearance 0.381)
			(thermal_gap 0.381)
		)
		(pad "A1" smd rect
			(at 2.29997 -7.994904 90)
			(size 0.381 1.27)
			(layers "F.Cu" "F.Mask" "F.Paste")
			(net "GND")
		)
		(pad "A2" smd rect
			(at 2.29997 -7.394956 90)
			(size 0.381 1.27)
			(layers "F.Cu" "F.Mask" "F.Paste")
			(net "GND")
		)
		(pad "A3" smd rect
			(at 2.29997 -6.795008 90)
			(size 0.381 1.27)
			(layers "F.Cu" "F.Mask" "F.Paste")
			(net "GND")
		)
		(pad "A4" smd rect
			(at 2.29997 -6.19506 90)
			(size 0.381 1.27)
			(layers "F.Cu" "F.Mask" "F.Paste")
			(net "GND")
		)
		(pad "A5" smd rect
			(at 2.29997 -5.595112 90)
			(size 0.381 1.27)
			(layers "F.Cu" "F.Mask" "F.Paste")
			(net "GND")
		)
		(pad "A6" smd rect
			(at 2.29997 -4.99491 90)
			(size 0.381 1.27)
			(layers "F.Cu" "F.Mask" "F.Paste")
			(net "GND")
		)
		(pad "A7" smd rect
			(at 2.29997 -4.394962 90)
			(size 0.381 1.27)
			(layers "F.Cu" "F.Mask" "F.Paste")
			(net "SMB_ISO_SSD15_R_SCL")
		)
		(pad "A8" smd rect
			(at 2.29997 -3.795014 90)
			(size 0.381 1.27)
			(layers "F.Cu" "F.Mask" "F.Paste")
			(net "SMB_ISO_SSD15_R_SDA")
		)
		(pad "A9" smd rect
			(at 2.29997 -3.195066 90)
			(size 0.381 1.27)
			(layers "F.Cu" "F.Mask" "F.Paste")
			(net "RST_SMB_SSD15_ISO_R_N")
		)
		(pad "A10" smd rect
			(at 2.29997 -2.595118 90)
			(size 0.381 1.27)
			(layers "F.Cu" "F.Mask" "F.Paste")
			(net "SSD15_LED_ISO_R_N")
		)
		(pad "A11" smd rect
			(at 2.29997 -1.994916 90)
			(size 0.381 1.27)
			(layers "F.Cu" "F.Mask" "F.Paste")
			(net "PU_CLKREQ15")
		)
		(pad "A12" smd rect
			(at 2.29997 -1.394968 90)
			(size 0.381 1.27)
			(layers "F.Cu" "F.Mask" "F.Paste")
			(net "PRSNT_SSD15_N")
		)
		(pad "A13" smd rect
			(at 2.29997 -0.79502 90)
			(size 0.381 1.27)
			(layers "F.Cu" "F.Mask" "F.Paste")
			(net "GND")
		)
		(pad "A14" smd rect
			(at 2.29997 -0.195072 90)
			(size 0.381 1.27)
			(layers "F.Cu" "F.Mask" "F.Paste")
			(net "Net_8459")
		)
		(pad "A15" smd rect
			(at 2.29997 0.404876 90)
			(size 0.381 1.27)
			(layers "F.Cu" "F.Mask" "F.Paste")
			(net "Net_8458")
		)
		(pad "A16" smd rect
			(at 2.29997 1.005078 90)
			(size 0.381 1.27)
			(layers "F.Cu" "F.Mask" "F.Paste")
			(net "GND")
		)
		(pad "A17" smd rect
			(at 2.29997 1.605026 90)
			(size 0.381 1.27)
			(layers "F.Cu" "F.Mask" "F.Paste")
			(net "P5E_PEX3_STN2_RX_DN<32>")
		)
		(pad "A18" smd rect
			(at 2.29997 2.204974 90)
			(size 0.381 1.27)
			(layers "F.Cu" "F.Mask" "F.Paste")
			(net "P5E_PEX3_STN2_RX_DP<32>")
		)
		(pad "A19" smd rect
			(at 2.29997 2.804922 90)
			(size 0.381 1.27)
			(layers "F.Cu" "F.Mask" "F.Paste")
			(net "GND")
		)
		(pad "A20" smd rect
			(at 2.29997 3.405124 90)
			(size 0.381 1.27)
			(layers "F.Cu" "F.Mask" "F.Paste")
			(net "P5E_PEX3_STN2_RX_DN<33>")
		)
		(pad "A21" smd rect
			(at 2.29997 4.005072 90)
			(size 0.381 1.27)
			(layers "F.Cu" "F.Mask" "F.Paste")
			(net "P5E_PEX3_STN2_RX_DP<33>")
		)
		(pad "A22" smd rect
			(at 2.29997 4.60502 90)
			(size 0.381 1.27)
			(layers "F.Cu" "F.Mask" "F.Paste")
			(net "GND")
		)
		(pad "A23" smd rect
			(at 2.29997 5.204968 90)
			(size 0.381 1.27)
			(layers "F.Cu" "F.Mask" "F.Paste")
			(net "P5E_PEX3_STN2_RX_DN<34>")
		)
		(pad "A24" smd rect
			(at 2.29997 5.804916 90)
			(size 0.381 1.27)
			(layers "F.Cu" "F.Mask" "F.Paste")
			(net "P5E_PEX3_STN2_RX_DP<34>")
		)
		(pad "A25" smd rect
			(at 2.29997 6.405118 90)
			(size 0.381 1.27)
			(layers "F.Cu" "F.Mask" "F.Paste")
			(net "GND")
		)
		(pad "A26" smd rect
			(at 2.29997 7.005066 90)
			(size 0.381 1.27)
			(layers "F.Cu" "F.Mask" "F.Paste")
			(net "P5E_PEX3_STN2_RX_DN<35>")
		)
		(pad "A27" smd rect
			(at 2.29997 7.605014 90)
			(size 0.381 1.27)
			(layers "F.Cu" "F.Mask" "F.Paste")
			(net "P5E_PEX3_STN2_RX_DP<35>")
		)
		(pad "A28" smd rect
			(at 2.29997 8.204962 90)
			(size 0.381 1.27)
			(layers "F.Cu" "F.Mask" "F.Paste")
			(net "GND")
		)
		(pad "B1" smd rect
			(at -2.29997 -7.994904 90)
			(size 0.381 1.27)
			(layers "F.Cu" "F.Mask" "F.Paste")
			(net "P12V_SSD15")
		)
		(pad "B2" smd rect
			(at -2.29997 -7.394956 90)
			(size 0.381 1.27)
			(layers "F.Cu" "F.Mask" "F.Paste")
			(net "P12V_SSD15")
		)
		(pad "B3" smd rect
			(at -2.29997 -6.795008 90)
			(size 0.381 1.27)
			(layers "F.Cu" "F.Mask" "F.Paste")
			(net "P12V_SSD15")
		)
		(pad "B4" smd rect
			(at -2.29997 -6.19506 90)
			(size 0.381 1.27)
			(layers "F.Cu" "F.Mask" "F.Paste")
			(net "P12V_SSD15")
		)
		(pad "B5" smd rect
			(at -2.29997 -5.595112 90)
			(size 0.381 1.27)
			(layers "F.Cu" "F.Mask" "F.Paste")
			(net "P12V_SSD15")
		)
		(pad "B6" smd rect
			(at -2.29997 -4.99491 90)
			(size 0.381 1.27)
			(layers "F.Cu" "F.Mask" "F.Paste")
			(net "P12V_SSD15")
		)
		(pad "B7" smd rect
			(at -2.29997 -4.394962 90)
			(size 0.381 1.27)
			(layers "F.Cu" "F.Mask" "F.Paste")
			(net "Net_8460")
		)
		(pad "B8" smd rect
			(at -2.29997 -3.795014 90)
			(size 0.381 1.27)
			(layers "F.Cu" "F.Mask" "F.Paste")
			(net "Net_8457")
		)
		(pad "B9" smd rect
			(at -2.29997 -3.195066 90)
			(size 0.381 1.27)
			(layers "F.Cu" "F.Mask" "F.Paste")
			(net "DUALPORT_N_SSD15")
		)
		(pad "B10" smd rect
			(at -2.29997 -2.595118 90)
			(size 0.381 1.27)
			(layers "F.Cu" "F.Mask" "F.Paste")
			(net "RST_SSD15_PERST_R_N")
		)
		(pad "B11" smd rect
			(at -2.29997 -1.994916 90)
			(size 0.381 1.27)
			(layers "F.Cu" "F.Mask" "F.Paste")
			(net "P3V3_SSD15")
		)
		(pad "B12" smd rect
			(at -2.29997 -1.394968 90)
			(size 0.381 1.27)
			(layers "F.Cu" "F.Mask" "F.Paste")
			(net "SSD15_PWRDIS_R")
		)
		(pad "B13" smd rect
			(at -2.29997 -0.79502 90)
			(size 0.381 1.27)
			(layers "F.Cu" "F.Mask" "F.Paste")
			(net "GND")
		)
		(pad "B14" smd rect
			(at -2.29997 -0.195072 90)
			(size 0.381 1.27)
			(layers "F.Cu" "F.Mask" "F.Paste")
			(net "CLK_100M_DB800ZL_SSD15_R_DN")
		)
		(pad "B15" smd rect
			(at -2.29997 0.404876 90)
			(size 0.381 1.27)
			(layers "F.Cu" "F.Mask" "F.Paste")
			(net "CLK_100M_DB800ZL_SSD15_R_DP")
		)
		(pad "B16" smd rect
			(at -2.29997 1.005078 90)
			(size 0.381 1.27)
			(layers "F.Cu" "F.Mask" "F.Paste")
			(net "GND")
		)
		(pad "B17" smd rect
			(at -2.29997 1.605026 90)
			(size 0.381 1.27)
			(layers "F.Cu" "F.Mask" "F.Paste")
			(net "P5E_PEX3_STN2_TX_C_DN<32>")
		)
		(pad "B18" smd rect
			(at -2.29997 2.204974 90)
			(size 0.381 1.27)
			(layers "F.Cu" "F.Mask" "F.Paste")
			(net "P5E_PEX3_STN2_TX_C_DP<32>")
		)
		(pad "B19" smd rect
			(at -2.29997 2.804922 90)
			(size 0.381 1.27)
			(layers "F.Cu" "F.Mask" "F.Paste")
			(net "GND")
		)
		(pad "B20" smd rect
			(at -2.29997 3.405124 90)
			(size 0.381 1.27)
			(layers "F.Cu" "F.Mask" "F.Paste")
			(net "P5E_PEX3_STN2_TX_C_DN<33>")
		)
		(pad "B21" smd rect
			(at -2.29997 4.005072 90)
			(size 0.381 1.27)
			(layers "F.Cu" "F.Mask" "F.Paste")
			(net "P5E_PEX3_STN2_TX_C_DP<33>")
		)
		(pad "B22" smd rect
			(at -2.29997 4.60502 90)
			(size 0.381 1.27)
			(layers "F.Cu" "F.Mask" "F.Paste")
			(net "GND")
		)
		(pad "B23" smd rect
			(at -2.29997 5.204968 90)
			(size 0.381 1.27)
			(layers "F.Cu" "F.Mask" "F.Paste")
			(net "P5E_PEX3_STN2_TX_C_DN<34>")
		)
		(pad "B24" smd rect
			(at -2.29997 5.804916 90)
			(size 0.381 1.27)
			(layers "F.Cu" "F.Mask" "F.Paste")
			(net "P5E_PEX3_STN2_TX_C_DP<34>")
		)
		(pad "B25" smd rect
			(at -2.29997 6.405118 90)
			(size 0.381 1.27)
			(layers "F.Cu" "F.Mask" "F.Paste")
			(net "GND")
		)
		(pad "B26" smd rect
			(at -2.29997 7.005066 90)
			(size 0.381 1.27)
			(layers "F.Cu" "F.Mask" "F.Paste")
			(net "P5E_PEX3_STN2_TX_C_DN<35>")
		)
		(pad "B27" smd rect
			(at -2.29997 7.605014 90)
			(size 0.381 1.27)
			(layers "F.Cu" "F.Mask" "F.Paste")
			(net "P5E_PEX3_STN2_TX_C_DP<35>")
		)
		(pad "B28" smd rect
			(at -2.29997 8.204962 90)
			(size 0.381 1.27)
			(layers "F.Cu" "F.Mask" "F.Paste")
			(net "GND")
		)
		(pad "G1" thru_hole oval
			(at 0 -11.364976 90)
			(size 1.6256 3.4798)
			(drill oval 1.1176 2.4638)
			(layers "*.Cu" "*.Mask")
			(remove_unused_layers no)
			(net "GND")
			(clearance 0.127)
			(thermal_gap 0.127)
		)
		(pad "G2" thru_hole oval
			(at 0 11.364976 90)
			(size 1.6256 3.4798)
			(drill oval 1.1176 2.4638)
			(layers "*.Cu" "*.Mask")
			(remove_unused_layers no)
			(net "GND")
			(clearance 0.127)
			(thermal_gap 0.127)
		)
		(zone
			(layer "F.Cu")
			(hatch none 0.5)
			(connect_pads
				(clearance 0)
			)
			(min_thickness 0.25)
			(keepout
				(tracks not_allowed)
				(vias allowed)
				(pads allowed)
				(copperpour not_allowed)
				(footprints allowed)
			)
			(placement
				(enabled no)
				(sheetname "")
			)
			(fill
				(thermal_gap 0.5)
				(thermal_bridge_width 0.5)
				(island_removal_mode 0)
			)
			(polygon
				(pts
					(xy 440.644788 -38.850062) (xy 437.89473 -38.850062) (xy 437.89473 -35.900106) (xy 440.644788 -35.900106)
				)
			)
		)
		(zone
			(layer "F.Cu")
			(hatch none 0.5)
			(connect_pads
				(clearance 0)
			)
			(min_thickness 0.25)
			(keepout
				(tracks not_allowed)
				(vias allowed)
				(pads allowed)
				(copperpour not_allowed)
				(footprints allowed)
			)
			(placement
				(enabled no)
				(sheetname "")
			)
			(fill
				(thermal_gap 0.5)
				(thermal_bridge_width 0.5)
				(island_removal_mode 0)
			)
			(polygon
				(pts
					(xy 441.71489 -17.670018) (xy 437.884824 -17.670018) (xy 437.884824 -14.720062) (xy 441.71489 -14.720062)
				)
			)
		)
		(zone
			(layers "F.Cu" "B.Cu" "In1.Cu" "In2.Cu" "In3.Cu" "In4.Cu" "In5.Cu" "In6.Cu"
				"In7.Cu" "In8.Cu" "In9.Cu" "In10.Cu" "In11.Cu" "In12.Cu" "In13.Cu" "In14.Cu"
				"In15.Cu" "In16.Cu"
			)
			(hatch none 0.5)
			(connect_pads
				(clearance 0)
			)
			(min_thickness 0.25)
			(keepout
				(tracks not_allowed)
				(vias allowed)
				(pads allowed)
				(copperpour not_allowed)
				(footprints allowed)
			)
			(placement
				(enabled no)
				(sheetname "")
			)
			(fill
				(thermal_gap 0.5)
				(thermal_bridge_width 0.5)
				(island_removal_mode 0)
			)
			(polygon
				(pts
					(arc
						(start 440.230006 -36.60013)
						(mid 438.299606 -36.60013)
						(end 440.230006 -36.60013)
					)
				)
			)
		)
		(zone
			(layers "F.Cu" "B.Cu" "In1.Cu" "In2.Cu" "In3.Cu" "In4.Cu" "In5.Cu" "In6.Cu"
				"In7.Cu" "In8.Cu" "In9.Cu" "In10.Cu" "In11.Cu" "In12.Cu" "In13.Cu" "In14.Cu"
				"In15.Cu" "In16.Cu"
			)
			(hatch none 0.5)
			(connect_pads
				(clearance 0)
			)
			(min_thickness 0.25)
			(keepout
				(tracks not_allowed)
				(vias allowed)
				(pads allowed)
				(copperpour not_allowed)
				(footprints allowed)
			)
			(placement
				(enabled no)
				(sheetname "")
			)
			(fill
				(thermal_gap 0.5)
				(thermal_bridge_width 0.5)
				(island_removal_mode 0)
			)
			(polygon
				(pts
					(arc
						(start 441.980066 -16.969994)
						(mid 440.049666 -16.969994)
						(end 441.980066 -16.969994)
					)
				)
			)
		)
	)
	(footprint ""
		(layer "F.Cu")
		(at 362.459016 -319.420494 90)
		(property "Reference" "R5798"
			(at 0 0 90)
			(layer "F.SilkS")
			(hide yes)
			(effects
				(font
					(size 1.27 1.27)
				)
			)
		)
		(property "Value" ""
			(at 0 0 90)
			(layer "F.Fab")
			(effects
				(font
					(size 1.27 1.27)
				)
			)
		)
		(duplicate_pad_numbers_are_jumpers no)
		(fp_line
			(start 2.576322 -1.1303)
			(end 2.576322 1.1303)
			(stroke
				(width 0.1524)
				(type default)
			)
			(layer "F.SilkS")
		)
		(fp_line
			(start -2.576322 -1.1303)
			(end 2.576322 -1.1303)
			(stroke
				(width 0.1524)
				(type default)
			)
			(layer "F.SilkS")
		)
		(fp_line
			(start 2.576322 1.1303)
			(end -2.576322 1.1303)
			(stroke
				(width 0.1524)
				(type default)
			)
			(layer "F.SilkS")
		)
		(fp_line
			(start -2.576322 1.1303)
			(end -2.576322 -1.1303)
			(stroke
				(width 0.1524)
				(type default)
			)
			(layer "F.SilkS")
		)
		(fp_line
			(start 1.649984 -0.899922)
			(end -1.649984 -0.899922)
			(stroke
				(width 0.1)
				(type default)
			)
			(layer "F.Fab")
		)
		(fp_line
			(start -1.649984 -0.899922)
			(end -1.649984 0.899922)
			(stroke
				(width 0.1)
				(type default)
			)
			(layer "F.Fab")
		)
		(fp_line
			(start 1.649984 0.899922)
			(end 1.649984 -0.899922)
			(stroke
				(width 0.1)
				(type default)
			)
			(layer "F.Fab")
		)
		(fp_line
			(start -1.649984 0.899922)
			(end 1.649984 0.899922)
			(stroke
				(width 0.1)
				(type default)
			)
			(layer "F.Fab")
		)
		(pad "1A" smd rect
			(at -1.700022 0 90)
			(size 1.4986 2.0066)
			(layers "F.Cu" "F.Mask" "F.Paste")
			(net "P0V8_PEX3")
		)
		(pad "1B" smd rect
			(at -1.077722 0 90)
			(size 0.254 0.508)
			(layers "F.Cu" "F.Mask" "F.Paste")
			(net "P0V8_PEX3")
		)
		(pad "2A" smd rect
			(at 1.700022 0 90)
			(size 1.4986 2.0066)
			(layers "F.Cu" "F.Mask" "F.Paste")
			(net "P0V8_SERDES_VDDA_PEX3")
		)
		(pad "2B" smd rect
			(at 1.077722 0 90)
			(size 0.254 0.508)
			(layers "F.Cu" "F.Mask" "F.Paste")
			(net "P0V8_SERDES_VDDA_PEX3")
		)
	)
	(footprint ""
		(layer "F.Cu")
		(at 140.731748 -343.952322 90)
		(property "Reference" "C2264"
			(at 0 0 90)
			(layer "F.SilkS")
			(hide yes)
			(effects
				(font
					(size 1.27 1.27)
				)
			)
		)
		(property "Value" ""
			(at 0 0 90)
			(layer "F.Fab")
			(effects
				(font
					(size 1.27 1.27)
				)
			)
		)
		(duplicate_pad_numbers_are_jumpers no)
		(fp_line
			(start 0.299974 -0.150114)
			(end 0.299974 0.150114)
			(stroke
				(width 0.1)
				(type default)
			)
			(layer "F.Fab")
		)
		(fp_line
			(start -0.299974 -0.150114)
			(end 0.299974 -0.150114)
			(stroke
				(width 0.1)
				(type default)
			)
			(layer "F.Fab")
		)
		(fp_line
			(start 0.299974 0.150114)
			(end -0.299974 0.150114)
			(stroke
				(width 0.1)
				(type default)
			)
			(layer "F.Fab")
		)
		(fp_line
			(start -0.299974 0.150114)
			(end -0.299974 -0.150114)
			(stroke
				(width 0.1)
				(type default)
			)
			(layer "F.Fab")
		)
		(pad "1" smd rect
			(at -0.2667 0 90)
			(size 0.3048 0.381)
			(layers "F.Cu" "F.Mask" "F.Paste")
			(net "P5E_PEX1_STN5_TX_DN<85>")
		)
		(pad "2" smd rect
			(at 0.2667 0 90)
			(size 0.3048 0.381)
			(layers "F.Cu" "F.Mask" "F.Paste")
			(net "P5E_PEX1_STN5_TX_C_DN<85>")
		)
	)
)
